# T6G (Grand Teton) — schematic netlist excerpt (pin names and nets, part order shuffled) for the footprints in the layout excerpt that follows; sources: Cadence DE-HDL packaged netlist, KiCad conversion of 04192023_DAF0TMB3IC0_F0TG_MB_C_brd_V02_OCP.brd

PC207  Q_CAP  560PF 50V 10% EMPTY  pkg C0402  page 220 : A = SW_PVDDCR_CPU1_P1_SW5 ; B = SW_PVDDCR_CPU1_P1_SW5_RC
R2114  Q_RES  0 5% CHIP  pkg 0402LF  page 145 : A = SMB_PCIE_E1S_ISO_EN_R2 ; B = SMB_PCIE_E1S_ISO_EN
C6574  Q_CAP_DIFFBUS  DIFF BUS_0.22UF 6.3V 20% X6S  pkg C0201  page 297 : \1\ = P5E_CPU0_P2_TX_BUF_C_DN<4> ; \2\ = P5E_CPU0_P2_TX_BUF_DN<4>

(kicad_pcb
	(version 20260206)
	(generator "pcbnew")
	(generator_version "10.0")
	(general
		(thickness 1.6)
		(legacy_teardrops no)
	)
	(paper "A4")
	(title_block
		(title "04192023_DAF0TMB3IC0_F0TG_MB_C_brd_V02_OCP.brd")
		(comment 1 "Grand Teton / footprints 4928-4930 of 8354")
	)
	(layers
		(0 "F.Cu" signal "TOP")
		(4 "In1.Cu" signal "GND")
		(6 "In2.Cu" signal "IN1")
		(8 "In3.Cu" signal "GND1")
		(10 "In4.Cu" signal "IN2")
		(12 "In5.Cu" signal "GND2")
		(14 "In6.Cu" signal "IN3")
		(16 "In7.Cu" signal "GND3")
		(18 "In8.Cu" signal "VCC")
		(20 "In9.Cu" signal "VCC1")
		(22 "In10.Cu" signal "GND4")
		(24 "In11.Cu" signal "IN4")
		(26 "In12.Cu" signal "GND5")
		(28 "In13.Cu" signal "IN5")
		(30 "In14.Cu" signal "GND6")
		(32 "In15.Cu" signal "IN6")
		(34 "In16.Cu" signal "GND7")
		(2 "B.Cu" signal "BOTTOM")
		(9 "F.Adhes" user "F.Adhesive")
		(11 "B.Adhes" user "B.Adhesive")
		(13 "F.Paste" user "Package Geometry/Pastemask Top")
		(15 "B.Paste" user "Package Geometry/Pastemask Bottom")
		(5 "F.SilkS" user "Ref Des/Silkscreen Top")
		(7 "B.SilkS" user "Ref Des/Silkscreen Bottom")
		(1 "F.Mask" user "Board Geometry/Soldermask Top")
		(3 "B.Mask" user "Board Geometry/Soldermask Bottom")
		(17 "Dwgs.User" user "User.Drawings")
		(19 "Cmts.User" user "User.Comments")
		(21 "Eco1.User" user "User.Eco1")
		(23 "Eco2.User" user "User.Eco2")
		(25 "Edge.Cuts" user "Board Geometry/Outline")
		(27 "Margin" user)
		(31 "F.CrtYd" user "Package Geometry/Place Bound Top")
		(29 "B.CrtYd" user "Package Geometry/Place Bound Bottom")
		(35 "F.Fab" user "Ref Des/Assembly Top")
		(33 "B.Fab" user "Ref Des/Assembly Bottom")
	)
	(footprint ""
		(layer "F.Cu")
		(at 91.759532 -332.02499 180)
		(property "Reference" "PC207"
			(at 0 0 180)
			(layer "F.SilkS")
			(hide yes)
			(effects
				(font
					(size 1.27 1.27)
				)
			)
		)
		(property "Value" ""
			(at 0 0 180)
			(layer "F.Fab")
			(effects
				(font
					(size 1.27 1.27)
				)
			)
		)
		(duplicate_pad_numbers_are_jumpers no)
		(fp_line
			(start 0.7874 0.4064)
			(end -0.7874 0.4064)
			(stroke
				(width 0.1524)
				(type default)
			)
			(layer "F.SilkS")
		)
		(fp_line
			(start 0.7874 -0.4064)
			(end 0.7874 0.4064)
			(stroke
				(width 0.1524)
				(type default)
			)
			(layer "F.SilkS")
		)
		(fp_line
			(start -0.7874 0.4064)
			(end -0.7874 -0.4064)
			(stroke
				(width 0.1524)
				(type default)
			)
			(layer "F.SilkS")
		)
		(fp_line
			(start -0.7874 -0.4064)
			(end 0.7874 -0.4064)
			(stroke
				(width 0.1524)
				(type default)
			)
			(layer "F.SilkS")
		)
		(fp_line
			(start 0.67945 0.3048)
			(end 0.120396 0.3048)
			(stroke
				(width 0.1)
				(type default)
			)
			(layer "F.Fab")
		)
		(fp_line
			(start 0.67945 -0.3048)
			(end 0.67945 0.3048)
			(stroke
				(width 0.1)
				(type default)
			)
			(layer "F.Fab")
		)
		(fp_line
			(start 0.12065 -0.2794)
			(end 0.12065 -0.3048)
			(stroke
				(width 0.1)
				(type default)
			)
			(layer "F.Fab")
		)
		(fp_line
			(start 0.12065 -0.3048)
			(end 0.67945 -0.3048)
			(stroke
				(width 0.1)
				(type default)
			)
			(layer "F.Fab")
		)
		(fp_line
			(start 0.120396 0.3048)
			(end 0.120396 0.2794)
			(stroke
				(width 0.1)
				(type default)
			)
			(layer "F.Fab")
		)
		(fp_line
			(start 0.120396 0.2794)
			(end -0.12065 0.2794)
			(stroke
				(width 0.1)
				(type default)
			)
			(layer "F.Fab")
		)
		(fp_line
			(start -0.12065 0.3048)
			(end -0.67945 0.3048)
			(stroke
				(width 0.1)
				(type default)
			)
			(layer "F.Fab")
		)
		(fp_line
			(start -0.12065 0.2794)
			(end -0.12065 0.3048)
			(stroke
				(width 0.1)
				(type default)
			)
			(layer "F.Fab")
		)
		(fp_line
			(start -0.12065 -0.2794)
			(end 0.12065 -0.2794)
			(stroke
				(width 0.1)
				(type default)
			)
			(layer "F.Fab")
		)
		(fp_line
			(start -0.12065 -0.305054)
			(end -0.12065 -0.2794)
			(stroke
				(width 0.1)
				(type default)
			)
			(layer "F.Fab")
		)
		(fp_line
			(start -0.67945 0.3048)
			(end -0.67945 -0.305054)
			(stroke
				(width 0.1)
				(type default)
			)
			(layer "F.Fab")
		)
		(fp_line
			(start -0.67945 -0.305054)
			(end -0.12065 -0.305054)
			(stroke
				(width 0.1)
				(type default)
			)
			(layer "F.Fab")
		)
		(pad "1" smd circle
			(at -0.40005 0 180)
			(size 0 0)
			(layers "F.Cu" "F.Mask" "F.Paste")
			(net "SW_PVDDCR_CPU1_P1_SW5")
		)
		(pad "2" smd circle
			(at 0.40005 0 180)
			(size 0 0)
			(layers "F.Cu" "F.Mask" "F.Paste")
			(net "SW_PVDDCR_CPU1_P1_SW5_RC")
		)
	)
	(footprint ""
		(layer "F.Cu")
		(at 383.121662 -416.899344 -90)
		(property "Reference" "C6574"
			(at 0 0 270)
			(layer "F.SilkS")
			(hide yes)
			(effects
				(font
					(size 1.27 1.27)
				)
			)
		)
		(property "Value" ""
			(at 0 0 270)
			(layer "F.Fab")
			(effects
				(font
					(size 1.27 1.27)
				)
			)
		)
		(duplicate_pad_numbers_are_jumpers no)
		(fp_line
			(start -0.299974 0.150114)
			(end -0.299974 -0.150114)
			(stroke
				(width 0.1)
				(type default)
			)
			(layer "F.Fab")
		)
		(fp_line
			(start 0.299974 0.150114)
			(end -0.299974 0.150114)
			(stroke
				(width 0.1)
				(type default)
			)
			(layer "F.Fab")
		)
		(fp_line
			(start -0.299974 -0.150114)
			(end 0.299974 -0.150114)
			(stroke
				(width 0.1)
				(type default)
			)
			(layer "F.Fab")
		)
		(fp_line
			(start 0.299974 -0.150114)
			(end 0.299974 0.150114)
			(stroke
				(width 0.1)
				(type default)
			)
			(layer "F.Fab")
		)
		(pad "1" smd rect
			(at -0.2667 0 270)
			(size 0.3048 0.381)
			(layers "F.Cu" "F.Mask" "F.Paste")
			(net "P5E_CPU0_P2_TX_BUF_C_DN<4>")
		)
		(pad "2" smd rect
			(at 0.2667 0 270)
			(size 0.3048 0.381)
			(layers "F.Cu" "F.Mask" "F.Paste")
			(net "P5E_CPU0_P2_TX_BUF_DN<4>")
		)
	)
	(footprint ""
		(layer "F.Cu")
		(at 258.275836 -72.976994)
		(property "Reference" "R2114"
			(at 0 0 0)
			(layer "F.SilkS")
			(hide yes)
			(effects
				(font
					(size 1.27 1.27)
				)
			)
		)
		(property "Value" ""
			(at 0 0 0)
			(layer "F.Fab")
			(effects
				(font
					(size 1.27 1.27)
				)
			)
		)
		(duplicate_pad_numbers_are_jumpers no)
		(fp_line
			(start -0.7874 -0.4064)
			(end 0.7874 -0.4064)
			(stroke
				(width 0.1524)
				(type default)
			)
			(layer "F.SilkS")
		)
		(fp_line
			(start -0.7874 0.4064)
			(end -0.7874 -0.4064)
			(stroke
				(width 0.1524)
				(type default)
			)
			(layer "F.SilkS")
		)
		(fp_line
			(start 0.7874 -0.4064)
			(end 0.7874 0.4064)
			(stroke
				(width 0.1524)
				(type default)
			)
			(layer "F.SilkS")
		)
		(fp_line
			(start 0.7874 0.4064)
			(end -0.7874 0.4064)
			(stroke
				(width 0.1524)
				(type default)
			)
			(layer "F.SilkS")
		)
		(fp_line
			(start -0.67945 -0.305054)
			(end -0.12065 -0.305054)
			(stroke
				(width 0.1)
				(type default)
			)
			(layer "F.Fab")
		)
		(fp_line
			(start -0.67945 0.3048)
			(end -0.67945 -0.305054)
			(stroke
				(width 0.1)
				(type default)
			)
			(layer "F.Fab")
		)
		(fp_line
			(start -0.12065 -0.305054)
			(end -0.12065 -0.2794)
			(stroke
				(width 0.1)
				(type default)
			)
			(layer "F.Fab")
		)
		(fp_line
			(start -0.12065 -0.2794)
			(end 0.12065 -0.2794)
			(stroke
				(width 0.1)
				(type default)
			)
			(layer "F.Fab")
		)
		(fp_line
			(start -0.12065 0.2794)
			(end -0.12065 0.3048)
			(stroke
				(width 0.1)
				(type default)
			)
			(layer "F.Fab")
		)
		(fp_line
			(start -0.12065 0.3048)
			(end -0.67945 0.3048)
			(stroke
				(width 0.1)
				(type default)
			)
			(layer "F.Fab")
		)
		(fp_line
			(start 0.120396 0.2794)
			(end -0.12065 0.2794)
			(stroke
				(width 0.1)
				(type default)
			)
			(layer "F.Fab")
		)
		(fp_line
			(start 0.120396 0.3048)
			(end 0.120396 0.2794)
			(stroke
				(width 0.1)
				(type default)
			)
			(layer "F.Fab")
		)
		(fp_line
			(start 0.12065 -0.3048)
			(end 0.67945 -0.3048)
			(stroke
				(width 0.1)
				(type default)
			)
			(layer "F.Fab")
		)
		(fp_line
			(start 0.12065 -0.2794)
			(end 0.12065 -0.3048)
			(stroke
				(width 0.1)
				(type default)
			)
			(layer "F.Fab")
		)
		(fp_line
			(start 0.67945 -0.3048)
			(end 0.67945 0.3048)
			(stroke
				(width 0.1)
				(type default)
			)
			(layer "F.Fab")
		)
		(fp_line
			(start 0.67945 0.3048)
			(end 0.120396 0.3048)
			(stroke
				(width 0.1)
				(type default)
			)
			(layer "F.Fab")
		)
		(pad "1" smd circle
			(at -0.40005 0)
			(size 0 0)
			(layers "F.Cu" "F.Mask" "F.Paste")
			(net "SMB_PCIE_E1S_ISO_EN_R2")
		)
		(pad "2" smd circle
			(at 0.40005 0)
			(size 0 0)
			(layers "F.Cu" "F.Mask" "F.Paste")
			(net "SMB_PCIE_E1S_ISO_EN")
		)
	)
)
